#ISCELL
  mstr_symbols intel_corp_bpage *
  *
#ISCELL
  mstr_symbols gnd *
  page124_i13
#ISCELL
  mstr_symbols gnd *
  page124_i14
#CELL
  mstr_u_proc lbg_core_qat_ext_d *
  page124_i15
#CELL
  mstr_u_proc lbg_core_qat_ext_d *
  page124_i16
#CELL
  mstr_u_proc lbg_core_qat_ext_d *
  page124_i17
#ISCELL
  mstr_symbols gnd *
  page124_i4
#ISCELL
  mstr_symbols gnd *
  page124_i6
#ISCELL
  mstr_symbols gnd *
  page124_i7
#ISCELL
  mstr_symbols gnd *
  page124_i9
